(kicad_pcb
	(version 20260206)
	(generator "pcbnew")
	(generator_version "10.0")
	(general
		(thickness 1.6)
		(legacy_teardrops no)
	)
	(paper "A4")
	(title_block
		(title "04192023_DAF0TMB3IC0_F0TG_MB_C_brd_V02_OCP.brd")
		(comment 1 "Grand Teton / footprints 5421-5427 of 8354")
	)
	(layers
		(0 "F.Cu" signal "TOP")
		(4 "In1.Cu" signal "GND")
		(6 "In2.Cu" signal "IN1")
		(8 "In3.Cu" signal "GND1")
		(10 "In4.Cu" signal "IN2")
		(12 "In5.Cu" signal "GND2")
		(14 "In6.Cu" signal "IN3")
		(16 "In7.Cu" signal "GND3")
		(18 "In8.Cu" signal "VCC")
		(20 "In9.Cu" signal "VCC1")
		(22 "In10.Cu" signal "GND4")
		(24 "In11.Cu" signal "IN4")
		(26 "In12.Cu" signal "GND5")
		(28 "In13.Cu" signal "IN5")
		(30 "In14.Cu" signal "GND6")
		(32 "In15.Cu" signal "IN6")
		(34 "In16.Cu" signal "GND7")
		(2 "B.Cu" signal "BOTTOM")
		(9 "F.Adhes" user "F.Adhesive")
		(11 "B.Adhes" user "B.Adhesive")
		(13 "F.Paste" user "Package Geometry/Pastemask Top")
		(15 "B.Paste" user "Package Geometry/Pastemask Bottom")
		(5 "F.SilkS" user "Ref Des/Silkscreen Top")
		(7 "B.SilkS" user "Ref Des/Silkscreen Bottom")
		(1 "F.Mask" user "Board Geometry/Soldermask Top")
		(3 "B.Mask" user "Board Geometry/Soldermask Bottom")
		(17 "Dwgs.User" user "User.Drawings")
		(19 "Cmts.User" user "User.Comments")
		(21 "Eco1.User" user "User.Eco1")
		(23 "Eco2.User" user "User.Eco2")
		(25 "Edge.Cuts" user "Board Geometry/Outline")
		(27 "Margin" user)
		(31 "F.CrtYd" user "Package Geometry/Place Bound Top")
		(29 "B.CrtYd" user "Package Geometry/Place Bound Bottom")
		(35 "F.Fab" user "Ref Des/Assembly Top")
		(33 "B.Fab" user "Ref Des/Assembly Bottom")
	)
	(footprint ""
		(layer "B.Cu")
		(at 238.633 -333.883 180)
		(property "Reference" "R801"
			(at 0 0 0)
			(layer "B.SilkS")
			(hide yes)
			(effects
				(font
					(size 1.27 1.27)
				)
				(justify mirror)
			)
		)
		(property "Value" ""
			(at 0 0 0)
			(layer "B.Fab")
			(effects
				(font
					(size 1.27 1.27)
				)
				(justify mirror)
			)
		)
		(duplicate_pad_numbers_are_jumpers no)
		(fp_line
			(start 0.32512 0.175006)
			(end 0.32512 -0.175006)
			(stroke
				(width 0.1)
				(type default)
			)
			(layer "B.Fab")
		)
		(fp_line
			(start 0.32512 -0.175006)
			(end -0.32512 -0.175006)
			(stroke
				(width 0.1)
				(type default)
			)
			(layer "B.Fab")
		)
		(fp_line
			(start -0.32512 0.175006)
			(end 0.32512 0.175006)
			(stroke
				(width 0.1)
				(type default)
			)
			(layer "B.Fab")
		)
		(fp_line
			(start -0.32512 -0.175006)
			(end -0.32512 0.175006)
			(stroke
				(width 0.1)
				(type default)
			)
			(layer "B.Fab")
		)
		(pad "1" smd rect
			(at 0.2667 0)
			(size 0.3048 0.381)
			(layers "B.Cu" "B.Mask" "B.Paste")
			(net "SMB_RT_CPU1_P0_ROM_MUX_2D_SDA")
		)
		(pad "2" smd rect
			(at -0.2667 0 180)
			(size 0.3048 0.381)
			(layers "B.Cu" "B.Mask" "B.Paste")
			(net "SMB_RT_CPU1_P0_ROM_MUX_2D_R_SDA")
		)
	)
	(footprint ""
		(layer "B.Cu")
		(at 317.702438 -199.998838)
		(property "Reference" "R6502"
			(at 0 0 0)
			(layer "B.SilkS")
			(hide yes)
			(effects
				(font
					(size 1.27 1.27)
				)
				(justify mirror)
			)
		)
		(property "Value" ""
			(at 0 0 0)
			(layer "B.Fab")
			(effects
				(font
					(size 1.27 1.27)
				)
				(justify mirror)
			)
		)
		(duplicate_pad_numbers_are_jumpers no)
		(fp_line
			(start -0.7874 -0.4064)
			(end -0.7874 0.4064)
			(stroke
				(width 0.1524)
				(type default)
			)
			(layer "B.SilkS")
		)
		(fp_line
			(start -0.7874 0.4064)
			(end 0.7874 0.4064)
			(stroke
				(width 0.1524)
				(type default)
			)
			(layer "B.SilkS")
		)
		(fp_line
			(start 0.7874 -0.4064)
			(end -0.7874 -0.4064)
			(stroke
				(width 0.1524)
				(type default)
			)
			(layer "B.SilkS")
		)
		(fp_line
			(start 0.7874 0.4064)
			(end 0.7874 -0.4064)
			(stroke
				(width 0.1524)
				(type default)
			)
			(layer "B.SilkS")
		)
		(fp_line
			(start -0.67945 -0.3048)
			(end -0.67945 0.3048)
			(stroke
				(width 0.1)
				(type default)
			)
			(layer "B.Fab")
		)
		(fp_line
			(start -0.67945 0.3048)
			(end -0.120396 0.3048)
			(stroke
				(width 0.1)
				(type default)
			)
			(layer "B.Fab")
		)
		(fp_line
			(start -0.12065 -0.3048)
			(end -0.67945 -0.3048)
			(stroke
				(width 0.1)
				(type default)
			)
			(layer "B.Fab")
		)
		(fp_line
			(start -0.12065 -0.2794)
			(end -0.12065 -0.3048)
			(stroke
				(width 0.1)
				(type default)
			)
			(layer "B.Fab")
		)
		(fp_line
			(start -0.120396 0.2794)
			(end 0.12065 0.2794)
			(stroke
				(width 0.1)
				(type default)
			)
			(layer "B.Fab")
		)
		(fp_line
			(start -0.120396 0.3048)
			(end -0.120396 0.2794)
			(stroke
				(width 0.1)
				(type default)
			)
			(layer "B.Fab")
		)
		(fp_line
			(start 0.12065 -0.305054)
			(end 0.12065 -0.2794)
			(stroke
				(width 0.1)
				(type default)
			)
			(layer "B.Fab")
		)
		(fp_line
			(start 0.12065 -0.2794)
			(end -0.12065 -0.2794)
			(stroke
				(width 0.1)
				(type default)
			)
			(layer "B.Fab")
		)
		(fp_line
			(start 0.12065 0.2794)
			(end 0.12065 0.3048)
			(stroke
				(width 0.1)
				(type default)
			)
			(layer "B.Fab")
		)
		(fp_line
			(start 0.12065 0.3048)
			(end 0.67945 0.3048)
			(stroke
				(width 0.1)
				(type default)
			)
			(layer "B.Fab")
		)
		(fp_line
			(start 0.67945 -0.305054)
			(end 0.12065 -0.305054)
			(stroke
				(width 0.1)
				(type default)
			)
			(layer "B.Fab")
		)
		(fp_line
			(start 0.67945 0.3048)
			(end 0.67945 -0.305054)
			(stroke
				(width 0.1)
				(type default)
			)
			(layer "B.Fab")
		)
		(pad "1" smd circle
			(at 0.40005 0 180)
			(size 0 0)
			(layers "B.Cu" "B.Mask" "B.Paste")
			(net "CPU0_FORCE_SELFREFRESH")
		)
		(pad "2" smd circle
			(at -0.40005 0 180)
			(size 0 0)
			(layers "B.Cu" "B.Mask" "B.Paste")
			(net "GND")
		)
	)
	(footprint ""
		(layer "B.Cu")
		(at 70.172834 -203.679552 180)
		(property "Reference" "R517"
			(at 0 0 0)
			(layer "B.SilkS")
			(hide yes)
			(effects
				(font
					(size 1.27 1.27)
				)
				(justify mirror)
			)
		)
		(property "Value" ""
			(at 0 0 0)
			(layer "B.Fab")
			(effects
				(font
					(size 1.27 1.27)
				)
				(justify mirror)
			)
		)
		(duplicate_pad_numbers_are_jumpers no)
		(fp_line
			(start 0.7874 0.4064)
			(end 0.7874 -0.4064)
			(stroke
				(width 0.1524)
				(type default)
			)
			(layer "B.SilkS")
		)
		(fp_line
			(start 0.7874 -0.4064)
			(end -0.7874 -0.4064)
			(stroke
				(width 0.1524)
				(type default)
			)
			(layer "B.SilkS")
		)
		(fp_line
			(start -0.7874 0.4064)
			(end 0.7874 0.4064)
			(stroke
				(width 0.1524)
				(type default)
			)
			(layer "B.SilkS")
		)
		(fp_line
			(start -0.7874 -0.4064)
			(end -0.7874 0.4064)
			(stroke
				(width 0.1524)
				(type default)
			)
			(layer "B.SilkS")
		)
		(fp_line
			(start 0.67945 0.3048)
			(end 0.67945 -0.305054)
			(stroke
				(width 0.1)
				(type default)
			)
			(layer "B.Fab")
		)
		(fp_line
			(start 0.67945 -0.305054)
			(end 0.12065 -0.305054)
			(stroke
				(width 0.1)
				(type default)
			)
			(layer "B.Fab")
		)
		(fp_line
			(start 0.12065 0.3048)
			(end 0.67945 0.3048)
			(stroke
				(width 0.1)
				(type default)
			)
			(layer "B.Fab")
		)
		(fp_line
			(start 0.12065 0.2794)
			(end 0.12065 0.3048)
			(stroke
				(width 0.1)
				(type default)
			)
			(layer "B.Fab")
		)
		(fp_line
			(start 0.12065 -0.2794)
			(end -0.12065 -0.2794)
			(stroke
				(width 0.1)
				(type default)
			)
			(layer "B.Fab")
		)
		(fp_line
			(start 0.12065 -0.305054)
			(end 0.12065 -0.2794)
			(stroke
				(width 0.1)
				(type default)
			)
			(layer "B.Fab")
		)
		(fp_line
			(start -0.120396 0.3048)
			(end -0.120396 0.2794)
			(stroke
				(width 0.1)
				(type default)
			)
			(layer "B.Fab")
		)
		(fp_line
			(start -0.120396 0.2794)
			(end 0.12065 0.2794)
			(stroke
				(width 0.1)
				(type default)
			)
			(layer "B.Fab")
		)
		(fp_line
			(start -0.12065 -0.2794)
			(end -0.12065 -0.3048)
			(stroke
				(width 0.1)
				(type default)
			)
			(layer "B.Fab")
		)
		(fp_line
			(start -0.12065 -0.3048)
			(end -0.67945 -0.3048)
			(stroke
				(width 0.1)
				(type default)
			)
			(layer "B.Fab")
		)
		(fp_line
			(start -0.67945 0.3048)
			(end -0.120396 0.3048)
			(stroke
				(width 0.1)
				(type default)
			)
			(layer "B.Fab")
		)
		(fp_line
			(start -0.67945 -0.3048)
			(end -0.67945 0.3048)
			(stroke
				(width 0.1)
				(type default)
			)
			(layer "B.Fab")
		)
		(pad "1" smd circle
			(at 0.40005 0)
			(size 0 0)
			(layers "B.Cu" "B.Mask" "B.Paste")
			(net "P3V3_AUX")
		)
		(pad "2" smd circle
			(at -0.40005 0)
			(size 0 0)
			(layers "B.Cu" "B.Mask" "B.Paste")
			(net "CPU1_SP5R2")
		)
	)
	(footprint ""
		(layer "B.Cu")
		(at 109.728 -417.83 -90)
		(property "Reference" "R3035"
			(at 0 0 90)
			(layer "B.SilkS")
			(hide yes)
			(effects
				(font
					(size 1.27 1.27)
				)
				(justify mirror)
			)
		)
		(property "Value" ""
			(at 0 0 90)
			(layer "B.Fab")
			(effects
				(font
					(size 1.27 1.27)
				)
				(justify mirror)
			)
		)
		(duplicate_pad_numbers_are_jumpers no)
		(fp_line
			(start -0.7874 0.4064)
			(end 0.7874 0.4064)
			(stroke
				(width 0.1524)
				(type default)
			)
			(layer "B.SilkS")
		)
		(fp_line
			(start 0.7874 0.4064)
			(end 0.7874 -0.4064)
			(stroke
				(width 0.1524)
				(type default)
			)
			(layer "B.SilkS")
		)
		(fp_line
			(start -0.7874 -0.4064)
			(end -0.7874 0.4064)
			(stroke
				(width 0.1524)
				(type default)
			)
			(layer "B.SilkS")
		)
		(fp_line
			(start 0.7874 -0.4064)
			(end -0.7874 -0.4064)
			(stroke
				(width 0.1524)
				(type default)
			)
			(layer "B.SilkS")
		)
		(fp_line
			(start -0.67945 0.3048)
			(end -0.120396 0.3048)
			(stroke
				(width 0.1)
				(type default)
			)
			(layer "B.Fab")
		)
		(fp_line
			(start -0.120396 0.3048)
			(end -0.120396 0.2794)
			(stroke
				(width 0.1)
				(type default)
			)
			(layer "B.Fab")
		)
		(fp_line
			(start 0.12065 0.3048)
			(end 0.67945 0.3048)
			(stroke
				(width 0.1)
				(type default)
			)
			(layer "B.Fab")
		)
		(fp_line
			(start 0.67945 0.3048)
			(end 0.67945 -0.305054)
			(stroke
				(width 0.1)
				(type default)
			)
			(layer "B.Fab")
		)
		(fp_line
			(start -0.120396 0.2794)
			(end 0.12065 0.2794)
			(stroke
				(width 0.1)
				(type default)
			)
			(layer "B.Fab")
		)
		(fp_line
			(start 0.12065 0.2794)
			(end 0.12065 0.3048)
			(stroke
				(width 0.1)
				(type default)
			)
			(layer "B.Fab")
		)
		(fp_line
			(start -0.12065 -0.2794)
			(end -0.12065 -0.3048)
			(stroke
				(width 0.1)
				(type default)
			)
			(layer "B.Fab")
		)
		(fp_line
			(start 0.12065 -0.2794)
			(end -0.12065 -0.2794)
			(stroke
				(width 0.1)
				(type default)
			)
			(layer "B.Fab")
		)
		(fp_line
			(start -0.67945 -0.3048)
			(end -0.67945 0.3048)
			(stroke
				(width 0.1)
				(type default)
			)
			(layer "B.Fab")
		)
		(fp_line
			(start -0.12065 -0.3048)
			(end -0.67945 -0.3048)
			(stroke
				(width 0.1)
				(type default)
			)
			(layer "B.Fab")
		)
		(fp_line
			(start 0.12065 -0.305054)
			(end 0.12065 -0.2794)
			(stroke
				(width 0.1)
				(type default)
			)
			(layer "B.Fab")
		)
		(fp_line
			(start 0.67945 -0.305054)
			(end 0.12065 -0.305054)
			(stroke
				(width 0.1)
				(type default)
			)
			(layer "B.Fab")
		)
		(pad "1" smd circle
			(at 0.40005 0 90)
			(size 0 0)
			(layers "B.Cu" "B.Mask" "B.Paste")
			(net "P3V3_AUX")
		)
		(pad "2" smd circle
			(at -0.40005 0 90)
			(size 0 0)
			(layers "B.Cu" "B.Mask" "B.Paste")
			(net "FM_SMB_2_ALERT_GPU_ISO_N")
		)
	)
	(footprint ""
		(layer "B.Cu")
		(at 164.949378 -17.417288 180)
		(property "Reference" "R329"
			(at 0 0 0)
			(layer "B.SilkS")
			(hide yes)
			(effects
				(font
					(size 1.27 1.27)
				)
				(justify mirror)
			)
		)
		(property "Value" ""
			(at 0 0 0)
			(layer "B.Fab")
			(effects
				(font
					(size 1.27 1.27)
				)
				(justify mirror)
			)
		)
		(duplicate_pad_numbers_are_jumpers no)
		(fp_line
			(start 0.7874 0.4064)
			(end 0.7874 -0.4064)
			(stroke
				(width 0.1524)
				(type default)
			)
			(layer "B.SilkS")
		)
		(fp_line
			(start 0.7874 -0.4064)
			(end -0.7874 -0.4064)
			(stroke
				(width 0.1524)
				(type default)
			)
			(layer "B.SilkS")
		)
		(fp_line
			(start -0.7874 0.4064)
			(end 0.7874 0.4064)
			(stroke
				(width 0.1524)
				(type default)
			)
			(layer "B.SilkS")
		)
		(fp_line
			(start -0.7874 -0.4064)
			(end -0.7874 0.4064)
			(stroke
				(width 0.1524)
				(type default)
			)
			(layer "B.SilkS")
		)
		(fp_line
			(start 0.67945 0.3048)
			(end 0.67945 -0.305054)
			(stroke
				(width 0.1)
				(type default)
			)
			(layer "B.Fab")
		)
		(fp_line
			(start 0.67945 -0.305054)
			(end 0.12065 -0.305054)
			(stroke
				(width 0.1)
				(type default)
			)
			(layer "B.Fab")
		)
		(fp_line
			(start 0.12065 0.3048)
			(end 0.67945 0.3048)
			(stroke
				(width 0.1)
				(type default)
			)
			(layer "B.Fab")
		)
		(fp_line
			(start 0.12065 0.2794)
			(end 0.12065 0.3048)
			(stroke
				(width 0.1)
				(type default)
			)
			(layer "B.Fab")
		)
		(fp_line
			(start 0.12065 -0.2794)
			(end -0.12065 -0.2794)
			(stroke
				(width 0.1)
				(type default)
			)
			(layer "B.Fab")
		)
		(fp_line
			(start 0.12065 -0.305054)
			(end 0.12065 -0.2794)
			(stroke
				(width 0.1)
				(type default)
			)
			(layer "B.Fab")
		)
		(fp_line
			(start -0.120396 0.3048)
			(end -0.120396 0.2794)
			(stroke
				(width 0.1)
				(type default)
			)
			(layer "B.Fab")
		)
		(fp_line
			(start -0.120396 0.2794)
			(end 0.12065 0.2794)
			(stroke
				(width 0.1)
				(type default)
			)
			(layer "B.Fab")
		)
		(fp_line
			(start -0.12065 -0.2794)
			(end -0.12065 -0.3048)
			(stroke
				(width 0.1)
				(type default)
			)
			(layer "B.Fab")
		)
		(fp_line
			(start -0.12065 -0.3048)
			(end -0.67945 -0.3048)
			(stroke
				(width 0.1)
				(type default)
			)
			(layer "B.Fab")
		)
		(fp_line
			(start -0.67945 0.3048)
			(end -0.120396 0.3048)
			(stroke
				(width 0.1)
				(type default)
			)
			(layer "B.Fab")
		)
		(fp_line
			(start -0.67945 -0.3048)
			(end -0.67945 0.3048)
			(stroke
				(width 0.1)
				(type default)
			)
			(layer "B.Fab")
		)
		(pad "1" smd circle
			(at 0.40005 0)
			(size 0 0)
			(layers "B.Cu" "B.Mask" "B.Paste")
			(net "SMB_PMBUS_3V3AUX_SDA")
		)
		(pad "2" smd circle
			(at -0.40005 0)
			(size 0 0)
			(layers "B.Cu" "B.Mask" "B.Paste")
			(net "P3V3_AUX")
		)
	)
	(footprint ""
		(layer "B.Cu")
		(at 372.321328 -137.008108 90)
		(property "Reference" "C5011"
			(at 0 0 90)
			(layer "B.SilkS")
			(hide yes)
			(effects
				(font
					(size 1.27 1.27)
				)
				(justify mirror)
			)
		)
		(property "Value" ""
			(at 0 0 90)
			(layer "B.Fab")
			(effects
				(font
					(size 1.27 1.27)
				)
				(justify mirror)
			)
		)
		(duplicate_pad_numbers_are_jumpers no)
		(fp_line
			(start 0.7874 -0.4064)
			(end -0.7874 -0.4064)
			(stroke
				(width 0.1524)
				(type default)
			)
			(layer "B.SilkS")
		)
		(fp_line
			(start -0.7874 -0.4064)
			(end -0.7874 0.4064)
			(stroke
				(width 0.1524)
				(type default)
			)
			(layer "B.SilkS")
		)
		(fp_line
			(start 0.7874 0.4064)
			(end 0.7874 -0.4064)
			(stroke
				(width 0.1524)
				(type default)
			)
			(layer "B.SilkS")
		)
		(fp_line
			(start -0.7874 0.4064)
			(end 0.7874 0.4064)
			(stroke
				(width 0.1524)
				(type default)
			)
			(layer "B.SilkS")
		)
		(fp_line
			(start 0.67945 -0.305054)
			(end 0.12065 -0.305054)
			(stroke
				(width 0.1)
				(type default)
			)
			(layer "B.Fab")
		)
		(fp_line
			(start 0.12065 -0.305054)
			(end 0.12065 -0.2794)
			(stroke
				(width 0.1)
				(type default)
			)
			(layer "B.Fab")
		)
		(fp_line
			(start -0.12065 -0.3048)
			(end -0.67945 -0.3048)
			(stroke
				(width 0.1)
				(type default)
			)
			(layer "B.Fab")
		)
		(fp_line
			(start -0.67945 -0.3048)
			(end -0.67945 0.3048)
			(stroke
				(width 0.1)
				(type default)
			)
			(layer "B.Fab")
		)
		(fp_line
			(start 0.12065 -0.2794)
			(end -0.12065 -0.2794)
			(stroke
				(width 0.1)
				(type default)
			)
			(layer "B.Fab")
		)
		(fp_line
			(start -0.12065 -0.2794)
			(end -0.12065 -0.3048)
			(stroke
				(width 0.1)
				(type default)
			)
			(layer "B.Fab")
		)
		(fp_line
			(start 0.12065 0.2794)
			(end 0.12065 0.3048)
			(stroke
				(width 0.1)
				(type default)
			)
			(layer "B.Fab")
		)
		(fp_line
			(start -0.120396 0.2794)
			(end 0.12065 0.2794)
			(stroke
				(width 0.1)
				(type default)
			)
			(layer "B.Fab")
		)
		(fp_line
			(start 0.67945 0.3048)
			(end 0.67945 -0.305054)
			(stroke
				(width 0.1)
				(type default)
			)
			(layer "B.Fab")
		)
		(fp_line
			(start 0.12065 0.3048)
			(end 0.67945 0.3048)
			(stroke
				(width 0.1)
				(type default)
			)
			(layer "B.Fab")
		)
		(fp_line
			(start -0.120396 0.3048)
			(end -0.120396 0.2794)
			(stroke
				(width 0.1)
				(type default)
			)
			(layer "B.Fab")
		)
		(fp_line
			(start -0.67945 0.3048)
			(end -0.120396 0.3048)
			(stroke
				(width 0.1)
				(type default)
			)
			(layer "B.Fab")
		)
		(pad "1" smd circle
			(at 0.40005 0 270)
			(size 0 0)
			(layers "B.Cu" "B.Mask" "B.Paste")
			(net "PVDDCR_CPU0_P0_PMALERT")
		)
		(pad "2" smd circle
			(at -0.40005 0 270)
			(size 0 0)
			(layers "B.Cu" "B.Mask" "B.Paste")
			(net "GND")
		)
	)
	(footprint ""
		(layer "B.Cu")
		(at 136.897872 -64.04229 90)
		(property "Reference" "R15"
			(at 0 0 90)
			(layer "B.SilkS")
			(hide yes)
			(effects
				(font
					(size 1.27 1.27)
				)
				(justify mirror)
			)
		)
		(property "Value" ""
			(at 0 0 90)
			(layer "B.Fab")
			(effects
				(font
					(size 1.27 1.27)
				)
				(justify mirror)
			)
		)
		(duplicate_pad_numbers_are_jumpers no)
		(fp_line
			(start 0.7874 -0.4064)
			(end -0.7874 -0.4064)
			(stroke
				(width 0.1524)
				(type default)
			)
			(layer "B.SilkS")
		)
		(fp_line
			(start -0.7874 -0.4064)
			(end -0.7874 0.4064)
			(stroke
				(width 0.1524)
				(type default)
			)
			(layer "B.SilkS")
		)
		(fp_line
			(start 0.7874 0.4064)
			(end 0.7874 -0.4064)
			(stroke
				(width 0.1524)
				(type default)
			)
			(layer "B.SilkS")
		)
		(fp_line
			(start -0.7874 0.4064)
			(end 0.7874 0.4064)
			(stroke
				(width 0.1524)
				(type default)
			)
			(layer "B.SilkS")
		)
		(fp_line
			(start 0.67945 -0.305054)
			(end 0.12065 -0.305054)
			(stroke
				(width 0.1)
				(type default)
			)
			(layer "B.Fab")
		)
		(fp_line
			(start 0.12065 -0.305054)
			(end 0.12065 -0.2794)
			(stroke
				(width 0.1)
				(type default)
			)
			(layer "B.Fab")
		)
		(fp_line
			(start -0.12065 -0.3048)
			(end -0.67945 -0.3048)
			(stroke
				(width 0.1)
				(type default)
			)
			(layer "B.Fab")
		)
		(fp_line
			(start -0.67945 -0.3048)
			(end -0.67945 0.3048)
			(stroke
				(width 0.1)
				(type default)
			)
			(layer "B.Fab")
		)
		(fp_line
			(start 0.12065 -0.2794)
			(end -0.12065 -0.2794)
			(stroke
				(width 0.1)
				(type default)
			)
			(layer "B.Fab")
		)
		(fp_line
			(start -0.12065 -0.2794)
			(end -0.12065 -0.3048)
			(stroke
				(width 0.1)
				(type default)
			)
			(layer "B.Fab")
		)
		(fp_line
			(start 0.12065 0.2794)
			(end 0.12065 0.3048)
			(stroke
				(width 0.1)
				(type default)
			)
			(layer "B.Fab")
		)
		(fp_line
			(start -0.120396 0.2794)
			(end 0.12065 0.2794)
			(stroke
				(width 0.1)
				(type default)
			)
			(layer "B.Fab")
		)
		(fp_line
			(start 0.67945 0.3048)
			(end 0.67945 -0.305054)
			(stroke
				(width 0.1)
				(type default)
			)
			(layer "B.Fab")
		)
		(fp_line
			(start 0.12065 0.3048)
			(end 0.67945 0.3048)
			(stroke
				(width 0.1)
				(type default)
			)
			(layer "B.Fab")
		)
		(fp_line
			(start -0.120396 0.3048)
			(end -0.120396 0.2794)
			(stroke
				(width 0.1)
				(type default)
			)
			(layer "B.Fab")
		)
		(fp_line
			(start -0.67945 0.3048)
			(end -0.120396 0.3048)
			(stroke
				(width 0.1)
				(type default)
			)
			(layer "B.Fab")
		)
		(pad "1" smd circle
			(at 0.40005 0 270)
			(size 0 0)
			(layers "B.Cu" "B.Mask" "B.Paste")
			(net "JTAG_PLD_TCK")
		)
		(pad "2" smd circle
			(at -0.40005 0 270)
			(size 0 0)
			(layers "B.Cu" "B.Mask" "B.Paste")
			(net "JTAG_SCM_PLD_TCK")
		)
	)
)
